# BASEBOARD_FAB2 (Tioga Pass) — schematic netlist excerpt (pin names and nets, part order shuffled) for the footprints in the layout excerpt that follows; sources: Cadence DE-HDL packaged netlist, KiCad conversion of Wiwynn_Tioga_Pass_MB.brd

R3D22  RES  240 1.0% EMPTY  pkg 0402  page 90 : A = PVCCIO_CPU1 ; B = PU_CPU1_FRMAGENT
C9B8  CAPP  330UF 10V 20% POSCAP  pkg 7343HLF  page 176 : A = P5V_USB ; B = GND
R8C14  RES  20.0 1% CHIP  pkg 0402  page 138 : A = SMB_HOST_STBY_LVC3_SCL_R1 ; B = SMB_HOST_STBY_LVC3_SCL

(kicad_pcb
	(version 20260206)
	(generator "pcbnew")
	(generator_version "10.0")
	(general
		(thickness 1.6)
		(legacy_teardrops no)
	)
	(paper "A4")
	(title_block
		(title "Wiwynn_Tioga_Pass_MB.brd")
		(comment 1 "Tioga Pass / footprints 652-654 of 4770")
	)
	(layers
		(0 "F.Cu" signal "TOP")
		(4 "In1.Cu" signal "L2GND")
		(6 "In2.Cu" signal "L3")
		(8 "In3.Cu" signal "L4GND")
		(10 "In4.Cu" signal "L5")
		(12 "In5.Cu" signal "L6GND")
		(14 "In6.Cu" signal "L7VCC")
		(16 "In7.Cu" signal "L8VCC")
		(18 "In8.Cu" signal "L9GND")
		(20 "In9.Cu" signal "L10")
		(22 "In10.Cu" signal "L11GND")
		(24 "In11.Cu" signal "L12")
		(26 "In12.Cu" signal "L13GND")
		(2 "B.Cu" signal "BOTTOM")
		(9 "F.Adhes" user "F.Adhesive")
		(11 "B.Adhes" user "B.Adhesive")
		(13 "F.Paste" user "Package Geometry/Pastemask Top")
		(15 "B.Paste" user "Package Geometry/Pastemask Bottom")
		(5 "F.SilkS" user "Ref Des/Silkscreen Top")
		(7 "B.SilkS" user "Ref Des/Silkscreen Bottom")
		(1 "F.Mask" user "Board Geometry/Soldermask Top")
		(3 "B.Mask" user "Board Geometry/Soldermask Bottom")
		(17 "Dwgs.User" user "User.Drawings")
		(19 "Cmts.User" user "User.Comments")
		(21 "Eco1.User" user "User.Eco1")
		(23 "Eco2.User" user "User.Eco2")
		(25 "Edge.Cuts" user "Board Geometry/Outline")
		(27 "Margin" user)
		(31 "F.CrtYd" user "Package Geometry/Place Bound Top")
		(29 "B.CrtYd" user "Package Geometry/Place Bound Bottom")
		(35 "F.Fab" user "Ref Des/Assembly Top")
		(33 "B.Fab" user "Ref Des/Assembly Bottom")
	)
	(footprint ""
		(layer "F.Cu")
		(at 410.806138 -107.146598 90)
		(property "Reference" "R8C14"
			(at 0 0 90)
			(layer "F.SilkS")
			(hide yes)
			(effects
				(font
					(size 1.27 1.27)
				)
			)
		)
		(property "Value" ""
			(at 0 0 90)
			(layer "F.Fab")
			(effects
				(font
					(size 1.27 1.27)
				)
			)
		)
		(duplicate_pad_numbers_are_jumpers no)
		(fp_poly
			(pts
				(xy -0.2794 -0.1016) (xy 0.2794 -0.1016) (xy 0.2794 0.9906) (xy -0.2794 0.9906)
			)
			(stroke
				(width 0)
				(type default)
			)
			(fill no)
			(layer "F.CrtYd")
		)
		(fp_line
			(start 0.2794 -0.1016)
			(end -0.2794 -0.1016)
			(stroke
				(width 0.1)
				(type default)
			)
			(layer "F.Fab")
		)
		(fp_line
			(start -0.2794 -0.1016)
			(end -0.2794 0.9906)
			(stroke
				(width 0.1)
				(type default)
			)
			(layer "F.Fab")
		)
		(fp_line
			(start 0.2794 0.9906)
			(end 0.2794 -0.1016)
			(stroke
				(width 0.1)
				(type default)
			)
			(layer "F.Fab")
		)
		(fp_line
			(start -0.2794 0.9906)
			(end 0.2794 0.9906)
			(stroke
				(width 0.1)
				(type default)
			)
			(layer "F.Fab")
		)
		(pad "1" smd rect
			(at 0 0 90)
			(size 0.508 0.508)
			(layers "F.Cu" "F.Mask" "F.Paste")
			(net "SMB_HOST_STBY_LVC3_SCL_R1")
		)
		(pad "2" smd rect
			(at 0 0.889 90)
			(size 0.508 0.508)
			(layers "F.Cu" "F.Mask" "F.Paste")
			(net "SMB_HOST_STBY_LVC3_SCL")
		)
		(zone
			(layer "F.Cu")
			(hatch none 0.5)
			(connect_pads
				(clearance 0)
			)
			(min_thickness 0.25)
			(keepout
				(tracks allowed)
				(vias not_allowed)
				(pads allowed)
				(copperpour not_allowed)
				(footprints allowed)
			)
			(placement
				(enabled no)
				(sheetname "")
			)
			(fill
				(thermal_gap 0.5)
				(thermal_bridge_width 0.5)
				(island_removal_mode 0)
			)
			(polygon
				(pts
					(xy 411.060138 -106.892598) (xy 411.060138 -107.400598) (xy 411.441138 -107.400598) (xy 411.441138 -106.892598)
				)
			)
		)
		(zone
			(layer "F.Cu")
			(hatch none 0.5)
			(connect_pads
				(clearance 0)
			)
			(min_thickness 0.25)
			(keepout
				(tracks not_allowed)
				(vias allowed)
				(pads allowed)
				(copperpour not_allowed)
				(footprints allowed)
			)
			(placement
				(enabled no)
				(sheetname "")
			)
			(fill
				(thermal_gap 0.5)
				(thermal_bridge_width 0.5)
				(island_removal_mode 0)
			)
			(polygon
				(pts
					(xy 411.441138 -106.892598) (xy 411.441138 -107.400598) (xy 411.060138 -107.400598) (xy 411.060138 -106.892598)
				)
			)
		)
	)
	(footprint ""
		(layer "F.Cu")
		(at 109.728 -69.85)
		(property "Reference" "R3D22"
			(at 0 0 0)
			(layer "F.SilkS")
			(hide yes)
			(effects
				(font
					(size 1.27 1.27)
				)
			)
		)
		(property "Value" ""
			(at 0 0 0)
			(layer "F.Fab")
			(effects
				(font
					(size 1.27 1.27)
				)
			)
		)
		(duplicate_pad_numbers_are_jumpers no)
		(fp_poly
			(pts
				(xy -0.2794 -0.1016) (xy 0.2794 -0.1016) (xy 0.2794 0.9906) (xy -0.2794 0.9906)
			)
			(stroke
				(width 0)
				(type default)
			)
			(fill no)
			(layer "F.CrtYd")
		)
		(fp_line
			(start -0.2794 -0.1016)
			(end -0.2794 0.9906)
			(stroke
				(width 0.1)
				(type default)
			)
			(layer "F.Fab")
		)
		(fp_line
			(start -0.2794 0.9906)
			(end 0.2794 0.9906)
			(stroke
				(width 0.1)
				(type default)
			)
			(layer "F.Fab")
		)
		(fp_line
			(start 0.2794 -0.1016)
			(end -0.2794 -0.1016)
			(stroke
				(width 0.1)
				(type default)
			)
			(layer "F.Fab")
		)
		(fp_line
			(start 0.2794 0.9906)
			(end 0.2794 -0.1016)
			(stroke
				(width 0.1)
				(type default)
			)
			(layer "F.Fab")
		)
		(pad "1" smd rect
			(at 0 0)
			(size 0.508 0.508)
			(layers "F.Cu" "F.Mask" "F.Paste")
			(net "PVCCIO_CPU1")
		)
		(pad "2" smd rect
			(at 0 0.889)
			(size 0.508 0.508)
			(layers "F.Cu" "F.Mask" "F.Paste")
			(net "PU_CPU1_FRMAGENT")
		)
		(zone
			(layer "F.Cu")
			(hatch none 0.5)
			(connect_pads
				(clearance 0)
			)
			(min_thickness 0.25)
			(keepout
				(tracks allowed)
				(vias not_allowed)
				(pads allowed)
				(copperpour not_allowed)
				(footprints allowed)
			)
			(placement
				(enabled no)
				(sheetname "")
			)
			(fill
				(thermal_gap 0.5)
				(thermal_bridge_width 0.5)
				(island_removal_mode 0)
			)
			(polygon
				(pts
					(xy 109.474 -69.596) (xy 109.982 -69.596) (xy 109.982 -69.215) (xy 109.474 -69.215)
				)
			)
		)
		(zone
			(layer "F.Cu")
			(hatch none 0.5)
			(connect_pads
				(clearance 0)
			)
			(min_thickness 0.25)
			(keepout
				(tracks not_allowed)
				(vias allowed)
				(pads allowed)
				(copperpour not_allowed)
				(footprints allowed)
			)
			(placement
				(enabled no)
				(sheetname "")
			)
			(fill
				(thermal_gap 0.5)
				(thermal_bridge_width 0.5)
				(island_removal_mode 0)
			)
			(polygon
				(pts
					(xy 109.474 -69.215) (xy 109.982 -69.215) (xy 109.982 -69.596) (xy 109.474 -69.596)
				)
			)
		)
	)
	(footprint ""
		(layer "F.Cu")
		(at 464.312 -128.4986 -90)
		(property "Reference" "C9B8"
			(at 0 0 270)
			(layer "F.SilkS")
			(hide yes)
			(effects
				(font
					(size 1.27 1.27)
				)
			)
		)
		(property "Value" ""
			(at 0 0 270)
			(layer "F.Fab")
			(effects
				(font
					(size 1.27 1.27)
				)
			)
		)
		(duplicate_pad_numbers_are_jumpers no)
		(fp_line
			(start -2.2987 7.3533)
			(end -1.7272 7.3533)
			(stroke
				(width 0.1524)
				(type default)
			)
			(layer "F.SilkS")
		)
		(fp_line
			(start 1.7272 7.3533)
			(end 2.2987 7.3533)
			(stroke
				(width 0.1524)
				(type default)
			)
			(layer "F.SilkS")
		)
		(fp_line
			(start 2.2987 7.3533)
			(end 2.2987 -0.2413)
			(stroke
				(width 0.1524)
				(type default)
			)
			(layer "F.SilkS")
		)
		(fp_line
			(start -2.032 1.524)
			(end -1.7272 1.524)
			(stroke
				(width 0.1524)
				(type default)
			)
			(layer "F.SilkS")
		)
		(fp_line
			(start 2.032 1.524)
			(end 1.7272 1.524)
			(stroke
				(width 0.1524)
				(type default)
			)
			(layer "F.SilkS")
		)
		(fp_line
			(start -2.2987 -0.2413)
			(end -2.2987 7.3533)
			(stroke
				(width 0.1524)
				(type default)
			)
			(layer "F.SilkS")
		)
		(fp_line
			(start -2.032 -0.2413)
			(end -2.2987 -0.2413)
			(stroke
				(width 0.1524)
				(type default)
			)
			(layer "F.SilkS")
		)
		(fp_line
			(start 2.2987 -0.2413)
			(end 2.032 -0.2413)
			(stroke
				(width 0.1524)
				(type default)
			)
			(layer "F.SilkS")
		)
		(fp_line
			(start -2.032 -1.524)
			(end -2.032 1.524)
			(stroke
				(width 0.1524)
				(type default)
			)
			(layer "F.SilkS")
		)
		(fp_line
			(start -1.7272 -1.524)
			(end -2.032 -1.524)
			(stroke
				(width 0.1524)
				(type default)
			)
			(layer "F.SilkS")
		)
		(fp_line
			(start 1.7272 -1.524)
			(end 2.032 -1.524)
			(stroke
				(width 0.1524)
				(type default)
			)
			(layer "F.SilkS")
		)
		(fp_line
			(start 2.032 -1.524)
			(end 2.032 1.524)
			(stroke
				(width 0.1524)
				(type default)
			)
			(layer "F.SilkS")
		)
		(fp_poly
			(pts
				(xy -2.2987 -0.2413) (xy 2.2987 -0.2413) (xy 2.2987 7.3533) (xy -2.2987 7.3533)
			)
			(stroke
				(width 0)
				(type default)
			)
			(fill no)
			(layer "F.CrtYd")
		)
		(fp_line
			(start -2.2987 7.3533)
			(end -2.2987 -0.2413)
			(stroke
				(width 0.1)
				(type default)
			)
			(layer "F.Fab")
		)
		(fp_line
			(start 2.2987 7.3533)
			(end -2.2987 7.3533)
			(stroke
				(width 0.1)
				(type default)
			)
			(layer "F.Fab")
		)
		(fp_line
			(start -2.2987 -0.2413)
			(end 2.2987 -0.2413)
			(stroke
				(width 0.1)
				(type default)
			)
			(layer "F.Fab")
		)
		(fp_line
			(start 2.2987 -0.2413)
			(end 2.2987 7.3533)
			(stroke
				(width 0.1)
				(type default)
			)
			(layer "F.Fab")
		)
		(pad "1" smd rect
			(at 0 0 270)
			(size 2.54 3.048)
			(layers "F.Cu" "F.Mask" "F.Paste")
			(net "P5V_USB")
		)
		(pad "2" smd rect
			(at 0 7.112 270)
			(size 2.54 3.048)
			(layers "F.Cu" "F.Mask" "F.Paste")
			(net "GND")
		)
	)
)
